(kicad_pcb
	(version 20260206)
	(generator "pcbnew")
	(generator_version "10.0")
	(general
		(thickness 1.6)
		(legacy_teardrops no)
	)
	(paper "A4")
	(title_block
		(title "03242023_DA0F0TMBIJ0_F0T_Motherboard_J_brd_V01_OCP.brd")
		(comment 1 "Grand Teton / footprints 4099-4104 of 6105")
	)
	(layers
		(0 "F.Cu" signal "TOP")
		(4 "In1.Cu" signal "GND")
		(6 "In2.Cu" signal "IN1")
		(8 "In3.Cu" signal "GND1")
		(10 "In4.Cu" signal "IN2")
		(12 "In5.Cu" signal "GND2")
		(14 "In6.Cu" signal "IN3")
		(16 "In7.Cu" signal "GND3")
		(18 "In8.Cu" signal "VCC")
		(20 "In9.Cu" signal "VCC1")
		(22 "In10.Cu" signal "GND4")
		(24 "In11.Cu" signal "IN4")
		(26 "In12.Cu" signal "GND5")
		(28 "In13.Cu" signal "IN5")
		(30 "In14.Cu" signal "GND6")
		(32 "In15.Cu" signal "IN6")
		(34 "In16.Cu" signal "GND7")
		(2 "B.Cu" signal "BOTTOM")
		(9 "F.Adhes" user "F.Adhesive")
		(11 "B.Adhes" user "B.Adhesive")
		(13 "F.Paste" user "Package Geometry/Pastemask Top")
		(15 "B.Paste" user "Package Geometry/Pastemask Bottom")
		(5 "F.SilkS" user "Ref Des/Silkscreen Top")
		(7 "B.SilkS" user "Ref Des/Silkscreen Bottom")
		(1 "F.Mask" user "Board Geometry/Soldermask Top")
		(3 "B.Mask" user "Board Geometry/Soldermask Bottom")
		(17 "Dwgs.User" user "User.Drawings")
		(19 "Cmts.User" user "User.Comments")
		(21 "Eco1.User" user "User.Eco1")
		(23 "Eco2.User" user "User.Eco2")
		(25 "Edge.Cuts" user "Board Geometry/Outline")
		(27 "Margin" user)
		(31 "F.CrtYd" user "Package Geometry/Place Bound Top")
		(29 "B.CrtYd" user "Package Geometry/Place Bound Bottom")
		(35 "F.Fab" user "Ref Des/Assembly Top")
		(33 "B.Fab" user "Ref Des/Assembly Bottom")
	)
	(footprint ""
		(layer "F.Cu")
		(at 143.97355 -107.795568 180)
		(property "Reference" "C2254"
			(at 0 0 180)
			(layer "F.SilkS")
			(hide yes)
			(effects
				(font
					(size 1.27 1.27)
				)
			)
		)
		(property "Value" ""
			(at 0 0 180)
			(layer "F.Fab")
			(effects
				(font
					(size 1.27 1.27)
				)
			)
		)
		(duplicate_pad_numbers_are_jumpers no)
		(fp_line
			(start 0.7874 0.4064)
			(end -0.7874 0.4064)
			(stroke
				(width 0.1524)
				(type default)
			)
			(layer "F.SilkS")
		)
		(fp_line
			(start 0.7874 -0.4064)
			(end 0.7874 0.4064)
			(stroke
				(width 0.1524)
				(type default)
			)
			(layer "F.SilkS")
		)
		(fp_line
			(start -0.7874 0.4064)
			(end -0.7874 -0.4064)
			(stroke
				(width 0.1524)
				(type default)
			)
			(layer "F.SilkS")
		)
		(fp_line
			(start -0.7874 -0.4064)
			(end 0.7874 -0.4064)
			(stroke
				(width 0.1524)
				(type default)
			)
			(layer "F.SilkS")
		)
		(fp_line
			(start 0.67945 0.3048)
			(end 0.120396 0.3048)
			(stroke
				(width 0.1)
				(type default)
			)
			(layer "F.Fab")
		)
		(fp_line
			(start 0.67945 -0.3048)
			(end 0.67945 0.3048)
			(stroke
				(width 0.1)
				(type default)
			)
			(layer "F.Fab")
		)
		(fp_line
			(start 0.12065 -0.2794)
			(end 0.12065 -0.3048)
			(stroke
				(width 0.1)
				(type default)
			)
			(layer "F.Fab")
		)
		(fp_line
			(start 0.12065 -0.3048)
			(end 0.67945 -0.3048)
			(stroke
				(width 0.1)
				(type default)
			)
			(layer "F.Fab")
		)
		(fp_line
			(start 0.120396 0.3048)
			(end 0.120396 0.2794)
			(stroke
				(width 0.1)
				(type default)
			)
			(layer "F.Fab")
		)
		(fp_line
			(start 0.120396 0.2794)
			(end -0.12065 0.2794)
			(stroke
				(width 0.1)
				(type default)
			)
			(layer "F.Fab")
		)
		(fp_line
			(start -0.12065 0.3048)
			(end -0.67945 0.3048)
			(stroke
				(width 0.1)
				(type default)
			)
			(layer "F.Fab")
		)
		(fp_line
			(start -0.12065 0.2794)
			(end -0.12065 0.3048)
			(stroke
				(width 0.1)
				(type default)
			)
			(layer "F.Fab")
		)
		(fp_line
			(start -0.12065 -0.2794)
			(end 0.12065 -0.2794)
			(stroke
				(width 0.1)
				(type default)
			)
			(layer "F.Fab")
		)
		(fp_line
			(start -0.12065 -0.305054)
			(end -0.12065 -0.2794)
			(stroke
				(width 0.1)
				(type default)
			)
			(layer "F.Fab")
		)
		(fp_line
			(start -0.67945 0.3048)
			(end -0.67945 -0.305054)
			(stroke
				(width 0.1)
				(type default)
			)
			(layer "F.Fab")
		)
		(fp_line
			(start -0.67945 -0.305054)
			(end -0.12065 -0.305054)
			(stroke
				(width 0.1)
				(type default)
			)
			(layer "F.Fab")
		)
		(pad "1" smd circle
			(at -0.40005 0 180)
			(size 0 0)
			(layers "F.Cu" "F.Mask" "F.Paste")
			(net "P0V62_CPU0_ERRS_U306_VREF")
		)
		(pad "2" smd circle
			(at 0.40005 0 180)
			(size 0 0)
			(layers "F.Cu" "F.Mask" "F.Paste")
			(net "GND")
		)
	)
	(footprint ""
		(layer "F.Cu")
		(at 213.933786 -130.923538)
		(property "Reference" "U94"
			(at 1.224026 -1.897888 0)
			(unlocked yes)
			(layer "F.SilkS")
			(effects
				(font
					(size 0.7874 0.5842)
					(thickness 0.1524)
				)
			)
		)
		(property "Value" ""
			(at 0 0 0)
			(layer "F.Fab")
			(effects
				(font
					(size 1.27 1.27)
				)
			)
		)
		(duplicate_pad_numbers_are_jumpers no)
		(fp_line
			(start -1.640078 -1.100074)
			(end -1.640078 1.100074)
			(stroke
				(width 0.1524)
				(type default)
			)
			(layer "F.SilkS")
		)
		(fp_line
			(start -1.640078 1.100074)
			(end 1.640078 1.100074)
			(stroke
				(width 0.1524)
				(type default)
			)
			(layer "F.SilkS")
		)
		(fp_line
			(start 1.640078 -1.100074)
			(end -1.640078 -1.100074)
			(stroke
				(width 0.1524)
				(type default)
			)
			(layer "F.SilkS")
		)
		(fp_line
			(start 1.640078 1.100074)
			(end 1.640078 -1.100074)
			(stroke
				(width 0.1524)
				(type default)
			)
			(layer "F.SilkS")
		)
		(fp_poly
			(pts
				(xy -1.495044 -1.943354) (xy -0.725424 -1.943354) (xy -1.110234 -1.173734)
			)
			(stroke
				(width 0)
				(type default)
			)
			(fill yes)
			(layer "F.SilkS")
		)
		(fp_line
			(start -0.674878 -1.100074)
			(end -0.674878 1.100074)
			(stroke
				(width 0.1)
				(type default)
			)
			(layer "F.Fab")
		)
		(fp_line
			(start -0.674878 1.100074)
			(end 0.674878 1.100074)
			(stroke
				(width 0.1)
				(type default)
			)
			(layer "F.Fab")
		)
		(fp_line
			(start 0.674878 -1.100074)
			(end -0.674878 -1.100074)
			(stroke
				(width 0.1)
				(type default)
			)
			(layer "F.Fab")
		)
		(fp_line
			(start 0.674878 1.100074)
			(end 0.674878 -1.100074)
			(stroke
				(width 0.1)
				(type default)
			)
			(layer "F.Fab")
		)
		(fp_poly
			(pts
				(xy -1.74879 -0.649986) (xy -2.51841 -0.265176) (xy -2.51841 -1.034796)
			)
			(stroke
				(width 0)
				(type default)
			)
			(fill yes)
			(layer "F.Fab")
		)
		(pad "1" smd rect
			(at -0.818896 -0.649986 270)
			(size 0.3556 1.4732)
			(layers "F.Cu" "F.Mask" "F.Paste")
			(net "FM_COMP_P3V3_AUX_ENIN")
		)
		(pad "2" smd rect
			(at -0.818896 0 270)
			(size 0.3556 1.4732)
			(layers "F.Cu" "F.Mask" "F.Paste")
			(net "GND")
		)
		(pad "3" smd rect
			(at -0.818896 0.649986 270)
			(size 0.3556 1.4732)
			(layers "F.Cu" "F.Mask" "F.Paste")
			(net "FM_COMP_P3V3_AUX_VIN")
		)
		(pad "4" smd rect
			(at 0.818896 0.649986 270)
			(size 0.3556 1.4732)
			(layers "F.Cu" "F.Mask" "F.Paste")
			(net "PWRGD_DSW_PWROK_R1")
		)
		(pad "5" smd rect
			(at 0.818896 0 270)
			(size 0.3556 1.4732)
			(layers "F.Cu" "F.Mask" "F.Paste")
			(net "FM_COMP_P3V3_STBY_CEXT")
		)
		(pad "6" smd rect
			(at 0.818896 -0.649986 270)
			(size 0.3556 1.4732)
			(layers "F.Cu" "F.Mask" "F.Paste")
			(net "P3V3_AUX")
		)
	)
	(footprint ""
		(layer "F.Cu")
		(at 183.54802 -419.47338 90)
		(property "Reference" "R4795"
			(at 0 0 90)
			(layer "F.SilkS")
			(hide yes)
			(effects
				(font
					(size 1.27 1.27)
				)
			)
		)
		(property "Value" ""
			(at 0 0 90)
			(layer "F.Fab")
			(effects
				(font
					(size 1.27 1.27)
				)
			)
		)
		(duplicate_pad_numbers_are_jumpers no)
		(fp_line
			(start 0.7874 -0.4064)
			(end 0.7874 0.4064)
			(stroke
				(width 0.1524)
				(type default)
			)
			(layer "F.SilkS")
		)
		(fp_line
			(start -0.7874 -0.4064)
			(end 0.7874 -0.4064)
			(stroke
				(width 0.1524)
				(type default)
			)
			(layer "F.SilkS")
		)
		(fp_line
			(start 0.7874 0.4064)
			(end -0.7874 0.4064)
			(stroke
				(width 0.1524)
				(type default)
			)
			(layer "F.SilkS")
		)
		(fp_line
			(start -0.7874 0.4064)
			(end -0.7874 -0.4064)
			(stroke
				(width 0.1524)
				(type default)
			)
			(layer "F.SilkS")
		)
		(fp_line
			(start -0.12065 -0.305054)
			(end -0.12065 -0.2794)
			(stroke
				(width 0.1)
				(type default)
			)
			(layer "F.Fab")
		)
		(fp_line
			(start -0.67945 -0.305054)
			(end -0.12065 -0.305054)
			(stroke
				(width 0.1)
				(type default)
			)
			(layer "F.Fab")
		)
		(fp_line
			(start 0.67945 -0.3048)
			(end 0.67945 0.3048)
			(stroke
				(width 0.1)
				(type default)
			)
			(layer "F.Fab")
		)
		(fp_line
			(start 0.12065 -0.3048)
			(end 0.67945 -0.3048)
			(stroke
				(width 0.1)
				(type default)
			)
			(layer "F.Fab")
		)
		(fp_line
			(start 0.12065 -0.2794)
			(end 0.12065 -0.3048)
			(stroke
				(width 0.1)
				(type default)
			)
			(layer "F.Fab")
		)
		(fp_line
			(start -0.12065 -0.2794)
			(end 0.12065 -0.2794)
			(stroke
				(width 0.1)
				(type default)
			)
			(layer "F.Fab")
		)
		(fp_line
			(start 0.120396 0.2794)
			(end -0.12065 0.2794)
			(stroke
				(width 0.1)
				(type default)
			)
			(layer "F.Fab")
		)
		(fp_line
			(start -0.12065 0.2794)
			(end -0.12065 0.3048)
			(stroke
				(width 0.1)
				(type default)
			)
			(layer "F.Fab")
		)
		(fp_line
			(start 0.67945 0.3048)
			(end 0.120396 0.3048)
			(stroke
				(width 0.1)
				(type default)
			)
			(layer "F.Fab")
		)
		(fp_line
			(start 0.120396 0.3048)
			(end 0.120396 0.2794)
			(stroke
				(width 0.1)
				(type default)
			)
			(layer "F.Fab")
		)
		(fp_line
			(start -0.12065 0.3048)
			(end -0.67945 0.3048)
			(stroke
				(width 0.1)
				(type default)
			)
			(layer "F.Fab")
		)
		(fp_line
			(start -0.67945 0.3048)
			(end -0.67945 -0.305054)
			(stroke
				(width 0.1)
				(type default)
			)
			(layer "F.Fab")
		)
		(pad "1" smd circle
			(at -0.40005 0 90)
			(size 0 0)
			(layers "F.Cu" "F.Mask" "F.Paste")
			(net "HSC_CSOUT")
		)
		(pad "2" smd circle
			(at 0.40005 0 90)
			(size 0 0)
			(layers "F.Cu" "F.Mask" "F.Paste")
			(net "HSC_OC_VOL")
		)
	)
	(footprint ""
		(layer "F.Cu")
		(at 113.92408 -106.238548 -90)
		(property "Reference" "R4043"
			(at 0 0 270)
			(layer "F.SilkS")
			(hide yes)
			(effects
				(font
					(size 1.27 1.27)
				)
			)
		)
		(property "Value" ""
			(at 0 0 270)
			(layer "F.Fab")
			(effects
				(font
					(size 1.27 1.27)
				)
			)
		)
		(duplicate_pad_numbers_are_jumpers no)
		(fp_line
			(start -0.7874 0.4064)
			(end -0.7874 -0.4064)
			(stroke
				(width 0.1524)
				(type default)
			)
			(layer "F.SilkS")
		)
		(fp_line
			(start 0.7874 0.4064)
			(end -0.7874 0.4064)
			(stroke
				(width 0.1524)
				(type default)
			)
			(layer "F.SilkS")
		)
		(fp_line
			(start -0.7874 -0.4064)
			(end 0.7874 -0.4064)
			(stroke
				(width 0.1524)
				(type default)
			)
			(layer "F.SilkS")
		)
		(fp_line
			(start 0.7874 -0.4064)
			(end 0.7874 0.4064)
			(stroke
				(width 0.1524)
				(type default)
			)
			(layer "F.SilkS")
		)
		(fp_line
			(start -0.67945 0.3048)
			(end -0.67945 -0.305054)
			(stroke
				(width 0.1)
				(type default)
			)
			(layer "F.Fab")
		)
		(fp_line
			(start -0.12065 0.3048)
			(end -0.67945 0.3048)
			(stroke
				(width 0.1)
				(type default)
			)
			(layer "F.Fab")
		)
		(fp_line
			(start 0.120396 0.3048)
			(end 0.120396 0.2794)
			(stroke
				(width 0.1)
				(type default)
			)
			(layer "F.Fab")
		)
		(fp_line
			(start 0.67945 0.3048)
			(end 0.120396 0.3048)
			(stroke
				(width 0.1)
				(type default)
			)
			(layer "F.Fab")
		)
		(fp_line
			(start -0.12065 0.2794)
			(end -0.12065 0.3048)
			(stroke
				(width 0.1)
				(type default)
			)
			(layer "F.Fab")
		)
		(fp_line
			(start 0.120396 0.2794)
			(end -0.12065 0.2794)
			(stroke
				(width 0.1)
				(type default)
			)
			(layer "F.Fab")
		)
		(fp_line
			(start -0.12065 -0.2794)
			(end 0.12065 -0.2794)
			(stroke
				(width 0.1)
				(type default)
			)
			(layer "F.Fab")
		)
		(fp_line
			(start 0.12065 -0.2794)
			(end 0.12065 -0.3048)
			(stroke
				(width 0.1)
				(type default)
			)
			(layer "F.Fab")
		)
		(fp_line
			(start 0.12065 -0.3048)
			(end 0.67945 -0.3048)
			(stroke
				(width 0.1)
				(type default)
			)
			(layer "F.Fab")
		)
		(fp_line
			(start 0.67945 -0.3048)
			(end 0.67945 0.3048)
			(stroke
				(width 0.1)
				(type default)
			)
			(layer "F.Fab")
		)
		(fp_line
			(start -0.67945 -0.305054)
			(end -0.12065 -0.305054)
			(stroke
				(width 0.1)
				(type default)
			)
			(layer "F.Fab")
		)
		(fp_line
			(start -0.12065 -0.305054)
			(end -0.12065 -0.2794)
			(stroke
				(width 0.1)
				(type default)
			)
			(layer "F.Fab")
		)
		(pad "1" smd circle
			(at -0.40005 0 270)
			(size 0 0)
			(layers "F.Cu" "F.Mask" "F.Paste")
			(net "RST_CPU0_DRAM_CD_PLD_LVT3_R_N")
		)
		(pad "2" smd circle
			(at 0.40005 0 270)
			(size 0 0)
			(layers "F.Cu" "F.Mask" "F.Paste")
			(net "RST_CPU0_DRAM_CD_PLD_LVT3_N")
		)
	)
	(footprint ""
		(layer "F.Cu")
		(at 300.21022 -421.41521 90)
		(property "Reference" "R4121"
			(at 0 0 90)
			(layer "F.SilkS")
			(hide yes)
			(effects
				(font
					(size 1.27 1.27)
				)
			)
		)
		(property "Value" ""
			(at 0 0 90)
			(layer "F.Fab")
			(effects
				(font
					(size 1.27 1.27)
				)
			)
		)
		(duplicate_pad_numbers_are_jumpers no)
		(fp_line
			(start 0.7874 -0.4064)
			(end 0.7874 0.4064)
			(stroke
				(width 0.1524)
				(type default)
			)
			(layer "F.SilkS")
		)
		(fp_line
			(start -0.7874 -0.4064)
			(end 0.7874 -0.4064)
			(stroke
				(width 0.1524)
				(type default)
			)
			(layer "F.SilkS")
		)
		(fp_line
			(start 0.7874 0.4064)
			(end -0.7874 0.4064)
			(stroke
				(width 0.1524)
				(type default)
			)
			(layer "F.SilkS")
		)
		(fp_line
			(start -0.7874 0.4064)
			(end -0.7874 -0.4064)
			(stroke
				(width 0.1524)
				(type default)
			)
			(layer "F.SilkS")
		)
		(fp_line
			(start -0.12065 -0.305054)
			(end -0.12065 -0.2794)
			(stroke
				(width 0.1)
				(type default)
			)
			(layer "F.Fab")
		)
		(fp_line
			(start -0.67945 -0.305054)
			(end -0.12065 -0.305054)
			(stroke
				(width 0.1)
				(type default)
			)
			(layer "F.Fab")
		)
		(fp_line
			(start 0.67945 -0.3048)
			(end 0.67945 0.3048)
			(stroke
				(width 0.1)
				(type default)
			)
			(layer "F.Fab")
		)
		(fp_line
			(start 0.12065 -0.3048)
			(end 0.67945 -0.3048)
			(stroke
				(width 0.1)
				(type default)
			)
			(layer "F.Fab")
		)
		(fp_line
			(start 0.12065 -0.2794)
			(end 0.12065 -0.3048)
			(stroke
				(width 0.1)
				(type default)
			)
			(layer "F.Fab")
		)
		(fp_line
			(start -0.12065 -0.2794)
			(end 0.12065 -0.2794)
			(stroke
				(width 0.1)
				(type default)
			)
			(layer "F.Fab")
		)
		(fp_line
			(start 0.120396 0.2794)
			(end -0.12065 0.2794)
			(stroke
				(width 0.1)
				(type default)
			)
			(layer "F.Fab")
		)
		(fp_line
			(start -0.12065 0.2794)
			(end -0.12065 0.3048)
			(stroke
				(width 0.1)
				(type default)
			)
			(layer "F.Fab")
		)
		(fp_line
			(start 0.67945 0.3048)
			(end 0.120396 0.3048)
			(stroke
				(width 0.1)
				(type default)
			)
			(layer "F.Fab")
		)
		(fp_line
			(start 0.120396 0.3048)
			(end 0.120396 0.2794)
			(stroke
				(width 0.1)
				(type default)
			)
			(layer "F.Fab")
		)
		(fp_line
			(start -0.12065 0.3048)
			(end -0.67945 0.3048)
			(stroke
				(width 0.1)
				(type default)
			)
			(layer "F.Fab")
		)
		(fp_line
			(start -0.67945 0.3048)
			(end -0.67945 -0.305054)
			(stroke
				(width 0.1)
				(type default)
			)
			(layer "F.Fab")
		)
		(pad "1" smd circle
			(at -0.40005 0 90)
			(size 0 0)
			(layers "F.Cu" "F.Mask" "F.Paste")
			(net "P3V3_AUX")
		)
		(pad "2" smd circle
			(at 0.40005 0 90)
			(size 0 0)
			(layers "F.Cu" "F.Mask" "F.Paste")
			(net "PRSNT_CABLE_GPU_B3_N")
		)
	)
	(footprint ""
		(layer "F.Cu")
		(at 133.53288 -74.259948 90)
		(property "Reference" "C554"
			(at 0 0 90)
			(layer "F.SilkS")
			(hide yes)
			(effects
				(font
					(size 1.27 1.27)
				)
			)
		)
		(property "Value" ""
			(at 0 0 90)
			(layer "F.Fab")
			(effects
				(font
					(size 1.27 1.27)
				)
			)
		)
		(duplicate_pad_numbers_are_jumpers no)
		(fp_line
			(start 0.7874 -0.4064)
			(end 0.7874 0.4064)
			(stroke
				(width 0.1524)
				(type default)
			)
			(layer "F.SilkS")
		)
		(fp_line
			(start -0.7874 -0.4064)
			(end 0.7874 -0.4064)
			(stroke
				(width 0.1524)
				(type default)
			)
			(layer "F.SilkS")
		)
		(fp_line
			(start 0.7874 0.4064)
			(end -0.7874 0.4064)
			(stroke
				(width 0.1524)
				(type default)
			)
			(layer "F.SilkS")
		)
		(fp_line
			(start -0.7874 0.4064)
			(end -0.7874 -0.4064)
			(stroke
				(width 0.1524)
				(type default)
			)
			(layer "F.SilkS")
		)
		(fp_line
			(start -0.12065 -0.305054)
			(end -0.12065 -0.2794)
			(stroke
				(width 0.1)
				(type default)
			)
			(layer "F.Fab")
		)
		(fp_line
			(start -0.67945 -0.305054)
			(end -0.12065 -0.305054)
			(stroke
				(width 0.1)
				(type default)
			)
			(layer "F.Fab")
		)
		(fp_line
			(start 0.67945 -0.3048)
			(end 0.67945 0.3048)
			(stroke
				(width 0.1)
				(type default)
			)
			(layer "F.Fab")
		)
		(fp_line
			(start 0.12065 -0.3048)
			(end 0.67945 -0.3048)
			(stroke
				(width 0.1)
				(type default)
			)
			(layer "F.Fab")
		)
		(fp_line
			(start 0.12065 -0.2794)
			(end 0.12065 -0.3048)
			(stroke
				(width 0.1)
				(type default)
			)
			(layer "F.Fab")
		)
		(fp_line
			(start -0.12065 -0.2794)
			(end 0.12065 -0.2794)
			(stroke
				(width 0.1)
				(type default)
			)
			(layer "F.Fab")
		)
		(fp_line
			(start 0.120396 0.2794)
			(end -0.12065 0.2794)
			(stroke
				(width 0.1)
				(type default)
			)
			(layer "F.Fab")
		)
		(fp_line
			(start -0.12065 0.2794)
			(end -0.12065 0.3048)
			(stroke
				(width 0.1)
				(type default)
			)
			(layer "F.Fab")
		)
		(fp_line
			(start 0.67945 0.3048)
			(end 0.120396 0.3048)
			(stroke
				(width 0.1)
				(type default)
			)
			(layer "F.Fab")
		)
		(fp_line
			(start 0.120396 0.3048)
			(end 0.120396 0.2794)
			(stroke
				(width 0.1)
				(type default)
			)
			(layer "F.Fab")
		)
		(fp_line
			(start -0.12065 0.3048)
			(end -0.67945 0.3048)
			(stroke
				(width 0.1)
				(type default)
			)
			(layer "F.Fab")
		)
		(fp_line
			(start -0.67945 0.3048)
			(end -0.67945 -0.305054)
			(stroke
				(width 0.1)
				(type default)
			)
			(layer "F.Fab")
		)
		(pad "1" smd circle
			(at -0.40005 0 90)
			(size 0 0)
			(layers "F.Cu" "F.Mask" "F.Paste")
			(net "P3V3_AUX_BMC_D")
		)
		(pad "2" smd circle
			(at 0.40005 0 90)
			(size 0 0)
			(layers "F.Cu" "F.Mask" "F.Paste")
			(net "GND")
		)
	)
)
